(kicad_pcb
	(version 20260206)
	(generator "pcbnew")
	(generator_version "10.0")
	(general
		(thickness 1.6)
		(legacy_teardrops no)
	)
	(paper "A4")
	(title_block
		(title "baseboard — 13948-1b.1110WZS1818.brd")
		(comment 1 "Honey Badger (Wiwynn) / footprints 1734-1741 of 2523")
	)
	(layers
		(0 "F.Cu" signal "TOP")
		(4 "In1.Cu" signal "L2GND")
		(6 "In2.Cu" signal "L3")
		(8 "In3.Cu" signal "L4VCC")
		(10 "In4.Cu" signal "L5VCC")
		(12 "In5.Cu" signal "L6")
		(14 "In6.Cu" signal "L7GND")
		(2 "B.Cu" signal "BOTTOM")
		(9 "F.Adhes" user "F.Adhesive")
		(11 "B.Adhes" user "B.Adhesive")
		(13 "F.Paste" user "Package Geometry/Pastemask Top")
		(15 "B.Paste" user "Package Geometry/Pastemask Bottom")
		(5 "F.SilkS" user "Ref Des/Silkscreen Top")
		(7 "B.SilkS" user "Ref Des/Silkscreen Bottom")
		(1 "F.Mask" user "Board Geometry/Soldermask Top")
		(3 "B.Mask" user "Board Geometry/Soldermask Bottom")
		(17 "Dwgs.User" user "User.Drawings")
		(19 "Cmts.User" user "User.Comments")
		(21 "Eco1.User" user "User.Eco1")
		(23 "Eco2.User" user "User.Eco2")
		(25 "Edge.Cuts" user "Board Geometry/Outline")
		(27 "Margin" user)
		(31 "F.CrtYd" user "Package Geometry/Place Bound Top")
		(29 "B.CrtYd" user "Package Geometry/Place Bound Bottom")
		(35 "F.Fab" user "Ref Des/Assembly Top")
		(33 "B.Fab" user "Ref Des/Assembly Bottom")
	)
	(footprint ""
		(layer "F.Cu")
		(at 111.76 -60.452)
		(property "Reference" "SR689"
			(at 0 0 0)
			(layer "F.SilkS")
			(hide yes)
			(effects
				(font
					(size 1.27 1.27)
				)
			)
		)
		(property "Value" "10KR2F-2-GP"
			(at 0.064008 -3.993896 0)
			(unlocked yes)
			(layer "F.Fab")
			(hide yes)
			(effects
				(font
					(size 1.016 1.016)
					(thickness 0.1524)
				)
			)
		)
		(property "Device Type" "R402H16"
			(at 0.064008 -5.517896 0)
			(unlocked yes)
			(layer "F.Fab")
			(hide yes)
			(effects
				(font
					(size 1.016 1.016)
					(thickness 0.1524)
				)
			)
		)
		(duplicate_pad_numbers_are_jumpers no)
		(fp_line
			(start -0.508 -0.9398)
			(end -0.508 0.9398)
			(stroke
				(width 0.1524)
				(type default)
			)
			(layer "F.SilkS")
		)
		(fp_line
			(start 0.508 -0.9398)
			(end -0.508 -0.9398)
			(stroke
				(width 0.1524)
				(type default)
			)
			(layer "F.SilkS")
		)
		(fp_rect
			(start -0.508 0.9398)
			(end 0.508 -0.9398)
			(stroke
				(width 0)
				(type default)
			)
			(fill no)
			(layer "F.CrtYd")
		)
		(fp_rect
			(start -0.508 0.9398)
			(end 0.508 -0.9398)
			(stroke
				(width 0)
				(type default)
			)
			(fill no)
			(layer "F.Fab")
		)
		(pad "1" smd custom
			(at 0 -0.4445)
			(size 0.1397 0.1397)
			(layers "F.Cu" "F.Mask" "F.Paste")
			(net "P1V8_C")
			(options
				(clearance outline)
				(anchor circle)
			)
			(primitives
				(gr_poly
					(pts
						(arc
							(start -0.1778 -0.2794)
							(mid -0.249642 -0.249642)
							(end -0.2794 -0.1778)
						)
						(arc
							(start -0.2794 0.1778)
							(mid -0.249642 0.249642)
							(end -0.1778 0.2794)
						)
						(arc
							(start 0.1778 0.2794)
							(mid 0.249642 0.249642)
							(end 0.2794 0.1778)
						)
						(arc
							(start 0.2794 -0.1778)
							(mid 0.249642 -0.249642)
							(end 0.1778 -0.2794)
						)
					)
					(width 0)
					(fill yes)
				)
			)
		)
		(pad "2" smd custom
			(at 0 0.4445)
			(size 0.1397 0.1397)
			(layers "F.Cu" "F.Mask" "F.Paste")
			(net "XM_ADDR_0")
			(options
				(clearance outline)
				(anchor circle)
			)
			(primitives
				(gr_poly
					(pts
						(arc
							(start -0.1778 -0.2794)
							(mid -0.249642 -0.249642)
							(end -0.2794 -0.1778)
						)
						(arc
							(start -0.2794 0.1778)
							(mid -0.249642 0.249642)
							(end -0.1778 0.2794)
						)
						(arc
							(start 0.1778 0.2794)
							(mid 0.249642 0.249642)
							(end 0.2794 0.1778)
						)
						(arc
							(start 0.2794 -0.1778)
							(mid 0.249642 -0.249642)
							(end 0.1778 -0.2794)
						)
					)
					(width 0)
					(fill yes)
				)
			)
		)
	)
	(footprint ""
		(layer "F.Cu")
		(at 94.01937 -117.602)
		(property "Reference" "TP266"
			(at 0 0 0)
			(layer "F.SilkS")
			(hide yes)
			(effects
				(font
					(size 1.27 1.27)
				)
			)
		)
		(property "Value" "TPAD28"
			(at 0.0127 -1.8034 0)
			(unlocked yes)
			(layer "F.Fab")
			(hide yes)
			(effects
				(font
					(size 1.016 1.016)
					(thickness 0.1524)
				)
			)
		)
		(property "Device Type" "TPAD28"
			(at 0.0127 -3.3274 0)
			(unlocked yes)
			(layer "F.Fab")
			(hide yes)
			(effects
				(font
					(size 1.016 1.016)
					(thickness 0.1524)
				)
			)
		)
		(duplicate_pad_numbers_are_jumpers no)
		(fp_poly
			(pts
				(arc
					(start 0.3556 0)
					(mid -0.3556 0)
					(end 0.3556 0)
				)
			)
			(stroke
				(width 0)
				(type default)
			)
			(fill no)
			(layer "F.CrtYd")
		)
		(fp_poly
			(pts
				(arc
					(start 0.6096 0)
					(mid -0.6096 0)
					(end 0.6096 0)
				)
			)
			(stroke
				(width 0)
				(type default)
			)
			(fill no)
			(layer "F.Fab")
		)
		(pad "1" smd circle
			(at 0 0)
			(size 0.7112 0.7112)
			(layers "F.Cu" "F.Mask" "F.Paste")
			(net "SIO_LOAD_OUT")
		)
	)
	(footprint ""
		(layer "F.Cu")
		(at 184.404 -225.298 90)
		(property "Reference" "R1583"
			(at 0 0 90)
			(layer "F.SilkS")
			(hide yes)
			(effects
				(font
					(size 1.27 1.27)
				)
			)
		)
		(property "Value" "0R2J-2-GP"
			(at 0.064008 -3.993896 90)
			(unlocked yes)
			(layer "F.Fab")
			(hide yes)
			(effects
				(font
					(size 1.016 1.016)
					(thickness 0.1524)
				)
			)
		)
		(property "Device Type" "R402H16"
			(at 0.064008 -5.517896 90)
			(unlocked yes)
			(layer "F.Fab")
			(hide yes)
			(effects
				(font
					(size 1.016 1.016)
					(thickness 0.1524)
				)
			)
		)
		(duplicate_pad_numbers_are_jumpers no)
		(fp_line
			(start 0.508 -0.9398)
			(end -0.508 -0.9398)
			(stroke
				(width 0.1524)
				(type default)
			)
			(layer "F.SilkS")
		)
		(fp_line
			(start -0.508 -0.9398)
			(end -0.508 0.9398)
			(stroke
				(width 0.1524)
				(type default)
			)
			(layer "F.SilkS")
		)
		(fp_rect
			(start -0.508 0.9398)
			(end 0.508 -0.9398)
			(stroke
				(width 0)
				(type default)
			)
			(fill no)
			(layer "F.CrtYd")
		)
		(fp_rect
			(start -0.508 0.9398)
			(end 0.508 -0.9398)
			(stroke
				(width 0)
				(type default)
			)
			(fill no)
			(layer "F.Fab")
		)
		(pad "1" smd custom
			(at 0 -0.4445 90)
			(size 0.1397 0.1397)
			(layers "F.Cu" "F.Mask" "F.Paste")
			(net "SYS_PWRBTN_N")
			(options
				(clearance outline)
				(anchor circle)
			)
			(primitives
				(gr_poly
					(pts
						(arc
							(start -0.1778 -0.2794)
							(mid -0.249642 -0.249642)
							(end -0.2794 -0.1778)
						)
						(arc
							(start -0.2794 0.1778)
							(mid -0.249642 0.249642)
							(end -0.1778 0.2794)
						)
						(arc
							(start 0.1778 0.2794)
							(mid 0.249642 0.249642)
							(end 0.2794 0.1778)
						)
						(arc
							(start 0.2794 -0.1778)
							(mid 0.249642 -0.249642)
							(end 0.1778 -0.2794)
						)
					)
					(width 0)
					(fill yes)
				)
			)
		)
		(pad "2" smd custom
			(at 0 0.4445 90)
			(size 0.1397 0.1397)
			(layers "F.Cu" "F.Mask" "F.Paste")
			(net "PWRBTN_FP_N")
			(options
				(clearance outline)
				(anchor circle)
			)
			(primitives
				(gr_poly
					(pts
						(arc
							(start -0.1778 -0.2794)
							(mid -0.249642 -0.249642)
							(end -0.2794 -0.1778)
						)
						(arc
							(start -0.2794 0.1778)
							(mid -0.249642 0.249642)
							(end -0.1778 0.2794)
						)
						(arc
							(start 0.1778 0.2794)
							(mid 0.249642 0.249642)
							(end 0.2794 0.1778)
						)
						(arc
							(start 0.2794 -0.1778)
							(mid 0.249642 -0.249642)
							(end 0.1778 -0.2794)
						)
					)
					(width 0)
					(fill yes)
				)
			)
		)
	)
	(footprint ""
		(layer "F.Cu")
		(at 274.193 -169.545 90)
		(property "Reference" "R472"
			(at 0 0 90)
			(layer "F.SilkS")
			(hide yes)
			(effects
				(font
					(size 1.27 1.27)
				)
			)
		)
		(property "Value" "10KR2F-2-GP"
			(at 0.064008 -3.993896 90)
			(unlocked yes)
			(layer "F.Fab")
			(hide yes)
			(effects
				(font
					(size 1.016 1.016)
					(thickness 0.1524)
				)
			)
		)
		(property "Device Type" "R402H16"
			(at 0.064008 -5.517896 90)
			(unlocked yes)
			(layer "F.Fab")
			(hide yes)
			(effects
				(font
					(size 1.016 1.016)
					(thickness 0.1524)
				)
			)
		)
		(duplicate_pad_numbers_are_jumpers no)
		(fp_line
			(start 0.508 -0.9398)
			(end -0.508 -0.9398)
			(stroke
				(width 0.1524)
				(type default)
			)
			(layer "F.SilkS")
		)
		(fp_line
			(start -0.508 -0.9398)
			(end -0.508 0.9398)
			(stroke
				(width 0.1524)
				(type default)
			)
			(layer "F.SilkS")
		)
		(fp_rect
			(start -0.508 0.9398)
			(end 0.508 -0.9398)
			(stroke
				(width 0)
				(type default)
			)
			(fill no)
			(layer "F.CrtYd")
		)
		(fp_rect
			(start -0.508 0.9398)
			(end 0.508 -0.9398)
			(stroke
				(width 0)
				(type default)
			)
			(fill no)
			(layer "F.Fab")
		)
		(pad "1" smd custom
			(at 0 -0.4445 90)
			(size 0.1397 0.1397)
			(layers "F.Cu" "F.Mask" "F.Paste")
			(net "P3V3_STBY")
			(options
				(clearance outline)
				(anchor circle)
			)
			(primitives
				(gr_poly
					(pts
						(arc
							(start -0.1778 -0.2794)
							(mid -0.249642 -0.249642)
							(end -0.2794 -0.1778)
						)
						(arc
							(start -0.2794 0.1778)
							(mid -0.249642 0.249642)
							(end -0.1778 0.2794)
						)
						(arc
							(start 0.1778 0.2794)
							(mid 0.249642 0.249642)
							(end 0.2794 0.1778)
						)
						(arc
							(start 0.2794 -0.1778)
							(mid 0.249642 -0.249642)
							(end 0.1778 -0.2794)
						)
					)
					(width 0)
					(fill yes)
				)
			)
		)
		(pad "2" smd custom
			(at 0 0.4445 90)
			(size 0.1397 0.1397)
			(layers "F.Cu" "F.Mask" "F.Paste")
			(net "BMC_MSB_I2C_E_ALERT_#")
			(options
				(clearance outline)
				(anchor circle)
			)
			(primitives
				(gr_poly
					(pts
						(arc
							(start -0.1778 -0.2794)
							(mid -0.249642 -0.249642)
							(end -0.2794 -0.1778)
						)
						(arc
							(start -0.2794 0.1778)
							(mid -0.249642 0.249642)
							(end -0.1778 0.2794)
						)
						(arc
							(start 0.1778 0.2794)
							(mid 0.249642 0.249642)
							(end 0.2794 0.1778)
						)
						(arc
							(start 0.2794 -0.1778)
							(mid 0.249642 -0.249642)
							(end 0.1778 -0.2794)
						)
					)
					(width 0)
					(fill yes)
				)
			)
		)
	)
	(footprint ""
		(layer "F.Cu")
		(at 348.390718 -149.837648 -90)
		(property "Reference" "R449"
			(at 0 0 270)
			(layer "F.SilkS")
			(hide yes)
			(effects
				(font
					(size 1.27 1.27)
				)
			)
		)
		(property "Value" "0R2J-2-GP"
			(at 0.064008 -3.993896 270)
			(unlocked yes)
			(layer "F.Fab")
			(hide yes)
			(effects
				(font
					(size 1.016 1.016)
					(thickness 0.1524)
				)
			)
		)
		(property "Device Type" "R402H16"
			(at 0.064008 -5.517896 270)
			(unlocked yes)
			(layer "F.Fab")
			(hide yes)
			(effects
				(font
					(size 1.016 1.016)
					(thickness 0.1524)
				)
			)
		)
		(duplicate_pad_numbers_are_jumpers no)
		(fp_line
			(start -0.508 -0.9398)
			(end -0.508 0.9398)
			(stroke
				(width 0.1524)
				(type default)
			)
			(layer "F.SilkS")
		)
		(fp_line
			(start 0.508 -0.9398)
			(end -0.508 -0.9398)
			(stroke
				(width 0.1524)
				(type default)
			)
			(layer "F.SilkS")
		)
		(fp_rect
			(start -0.508 0.9398)
			(end 0.508 -0.9398)
			(stroke
				(width 0)
				(type default)
			)
			(fill no)
			(layer "F.CrtYd")
		)
		(fp_rect
			(start -0.508 0.9398)
			(end 0.508 -0.9398)
			(stroke
				(width 0)
				(type default)
			)
			(fill no)
			(layer "F.Fab")
		)
		(pad "1" smd custom
			(at 0 -0.4445 270)
			(size 0.1397 0.1397)
			(layers "F.Cu" "F.Mask" "F.Paste")
			(net "BMC_USB2_HDP")
			(options
				(clearance outline)
				(anchor circle)
			)
			(primitives
				(gr_poly
					(pts
						(arc
							(start -0.1778 -0.2794)
							(mid -0.249642 -0.249642)
							(end -0.2794 -0.1778)
						)
						(arc
							(start -0.2794 0.1778)
							(mid -0.249642 0.249642)
							(end -0.1778 0.2794)
						)
						(arc
							(start 0.1778 0.2794)
							(mid 0.249642 0.249642)
							(end 0.2794 0.1778)
						)
						(arc
							(start 0.2794 -0.1778)
							(mid 0.249642 -0.249642)
							(end 0.1778 -0.2794)
						)
					)
					(width 0)
					(fill yes)
				)
			)
		)
		(pad "2" smd custom
			(at 0 0.4445 270)
			(size 0.1397 0.1397)
			(layers "F.Cu" "F.Mask" "F.Paste")
			(net "USB_P2_DP")
			(options
				(clearance outline)
				(anchor circle)
			)
			(primitives
				(gr_poly
					(pts
						(arc
							(start -0.1778 -0.2794)
							(mid -0.249642 -0.249642)
							(end -0.2794 -0.1778)
						)
						(arc
							(start -0.2794 0.1778)
							(mid -0.249642 0.249642)
							(end -0.1778 0.2794)
						)
						(arc
							(start 0.1778 0.2794)
							(mid 0.249642 0.249642)
							(end 0.2794 0.1778)
						)
						(arc
							(start 0.2794 -0.1778)
							(mid 0.249642 -0.249642)
							(end 0.1778 -0.2794)
						)
					)
					(width 0)
					(fill yes)
				)
			)
		)
	)
	(footprint ""
		(layer "F.Cu")
		(at 300.526958 -58.293 180)
		(property "Reference" "C283"
			(at 0 0 180)
			(layer "F.SilkS")
			(hide yes)
			(effects
				(font
					(size 1.27 1.27)
				)
			)
		)
		(property "Value" "SCD1U25V2KX-2-GP"
			(at 1.1811 -2.7051 180)
			(unlocked yes)
			(layer "F.Fab")
			(hide yes)
			(effects
				(font
					(size 1.016 1.016)
					(thickness 0.1524)
				)
			)
		)
		(property "Device Type" "C402H22"
			(at 1.1811 -4.2291 180)
			(unlocked yes)
			(layer "F.Fab")
			(hide yes)
			(effects
				(font
					(size 1.016 1.016)
					(thickness 0.1524)
				)
			)
		)
		(duplicate_pad_numbers_are_jumpers no)
		(fp_rect
			(start -0.4318 0.9525)
			(end 0.4318 -0.9525)
			(stroke
				(width 0)
				(type default)
			)
			(fill no)
			(layer "F.CrtYd")
		)
		(fp_rect
			(start -0.4318 0.9525)
			(end 0.4318 -0.9525)
			(stroke
				(width 0)
				(type default)
			)
			(fill no)
			(layer "F.Fab")
		)
		(pad "1" smd custom
			(at 0 -0.4445 180)
			(size 0.1524 0.1524)
			(layers "F.Cu" "F.Mask" "F.Paste")
			(net "P3V3_STBY")
			(options
				(clearance outline)
				(anchor circle)
			)
			(primitives
				(gr_poly
					(pts
						(arc
							(start 0.3048 -0.2032)
							(mid 0.275042 -0.275042)
							(end 0.2032 -0.3048)
						)
						(arc
							(start -0.2032 -0.3048)
							(mid -0.275042 -0.275042)
							(end -0.3048 -0.2032)
						)
						(arc
							(start -0.3048 0.2032)
							(mid -0.275042 0.275042)
							(end -0.2032 0.3048)
						)
						(arc
							(start 0.2032 0.3048)
							(mid 0.275042 0.275042)
							(end 0.3048 0.2032)
						)
					)
					(width 0)
					(fill yes)
				)
			)
		)
		(pad "2" smd custom
			(at 0 0.4445 180)
			(size 0.1524 0.1524)
			(layers "F.Cu" "F.Mask" "F.Paste")
			(net "GND")
			(options
				(clearance outline)
				(anchor circle)
			)
			(primitives
				(gr_poly
					(pts
						(arc
							(start 0.3048 -0.2032)
							(mid 0.275042 -0.275042)
							(end 0.2032 -0.3048)
						)
						(arc
							(start -0.2032 -0.3048)
							(mid -0.275042 -0.275042)
							(end -0.3048 -0.2032)
						)
						(arc
							(start -0.3048 0.2032)
							(mid -0.275042 0.275042)
							(end -0.2032 0.3048)
						)
						(arc
							(start 0.2032 0.3048)
							(mid 0.275042 0.275042)
							(end 0.3048 0.2032)
						)
					)
					(width 0)
					(fill yes)
				)
			)
		)
	)
	(footprint ""
		(layer "F.Cu")
		(at 111.03737 -77.5462)
		(property "Reference" "STP71"
			(at 0 0 0)
			(layer "F.SilkS")
			(hide yes)
			(effects
				(font
					(size 1.27 1.27)
				)
			)
		)
		(property "Value" "TPAD28"
			(at 0.0127 -1.8034 0)
			(unlocked yes)
			(layer "F.Fab")
			(hide yes)
			(effects
				(font
					(size 1.016 1.016)
					(thickness 0.1524)
				)
			)
		)
		(property "Device Type" "TPAD28"
			(at 0.0127 -3.3274 0)
			(unlocked yes)
			(layer "F.Fab")
			(hide yes)
			(effects
				(font
					(size 1.016 1.016)
					(thickness 0.1524)
				)
			)
		)
		(duplicate_pad_numbers_are_jumpers no)
		(fp_poly
			(pts
				(arc
					(start 0.3556 0)
					(mid -0.3556 0)
					(end 0.3556 0)
				)
			)
			(stroke
				(width 0)
				(type default)
			)
			(fill no)
			(layer "F.CrtYd")
		)
		(fp_poly
			(pts
				(arc
					(start 0.6096 0)
					(mid -0.6096 0)
					(end 0.6096 0)
				)
			)
			(stroke
				(width 0)
				(type default)
			)
			(fill no)
			(layer "F.Fab")
		)
		(pad "1" smd circle
			(at 0 0)
			(size 0.7112 0.7112)
			(layers "F.Cu" "F.Mask" "F.Paste")
			(net "EXP_TEST_MUX33")
		)
	)
	(footprint ""
		(layer "F.Cu")
		(at 98.05797 -118.3005 180)
		(property "Reference" "SR749"
			(at 0 0 180)
			(layer "F.SilkS")
			(hide yes)
			(effects
				(font
					(size 1.27 1.27)
				)
			)
		)
		(property "Value" "4K7R2F-GP"
			(at 0.064008 -3.993896 180)
			(unlocked yes)
			(layer "F.Fab")
			(hide yes)
			(effects
				(font
					(size 1.016 1.016)
					(thickness 0.1524)
				)
			)
		)
		(property "Device Type" "R402H16"
			(at 0.064008 -5.517896 180)
			(unlocked yes)
			(layer "F.Fab")
			(hide yes)
			(effects
				(font
					(size 1.016 1.016)
					(thickness 0.1524)
				)
			)
		)
		(duplicate_pad_numbers_are_jumpers no)
		(fp_line
			(start 0.508 -0.9398)
			(end -0.508 -0.9398)
			(stroke
				(width 0.1524)
				(type default)
			)
			(layer "F.SilkS")
		)
		(fp_line
			(start -0.508 -0.9398)
			(end -0.508 0.9398)
			(stroke
				(width 0.1524)
				(type default)
			)
			(layer "F.SilkS")
		)
		(fp_rect
			(start -0.508 0.9398)
			(end 0.508 -0.9398)
			(stroke
				(width 0)
				(type default)
			)
			(fill no)
			(layer "F.CrtYd")
		)
		(fp_rect
			(start -0.508 0.9398)
			(end 0.508 -0.9398)
			(stroke
				(width 0)
				(type default)
			)
			(fill no)
			(layer "F.Fab")
		)
		(pad "1" smd custom
			(at 0 -0.4445 180)
			(size 0.1397 0.1397)
			(layers "F.Cu" "F.Mask" "F.Paste")
			(net "SIO_LOAD_IN")
			(options
				(clearance outline)
				(anchor circle)
			)
			(primitives
				(gr_poly
					(pts
						(arc
							(start -0.1778 -0.2794)
							(mid -0.249642 -0.249642)
							(end -0.2794 -0.1778)
						)
						(arc
							(start -0.2794 0.1778)
							(mid -0.249642 0.249642)
							(end -0.1778 0.2794)
						)
						(arc
							(start 0.1778 0.2794)
							(mid 0.249642 0.249642)
							(end 0.2794 0.1778)
						)
						(arc
							(start 0.2794 -0.1778)
							(mid 0.249642 -0.249642)
							(end 0.1778 -0.2794)
						)
					)
					(width 0)
					(fill yes)
				)
			)
		)
		(pad "2" smd custom
			(at 0 0.4445 180)
			(size 0.1397 0.1397)
			(layers "F.Cu" "F.Mask" "F.Paste")
			(net "P1V8_E")
			(options
				(clearance outline)
				(anchor circle)
			)
			(primitives
				(gr_poly
					(pts
						(arc
							(start -0.1778 -0.2794)
							(mid -0.249642 -0.249642)
							(end -0.2794 -0.1778)
						)
						(arc
							(start -0.2794 0.1778)
							(mid -0.249642 0.249642)
							(end -0.1778 0.2794)
						)
						(arc
							(start 0.1778 0.2794)
							(mid 0.249642 0.249642)
							(end 0.2794 0.1778)
						)
						(arc
							(start 0.2794 -0.1778)
							(mid 0.249642 -0.249642)
							(end 0.1778 -0.2794)
						)
					)
					(width 0)
					(fill yes)
				)
			)
		)
	)
)
